(kicad_pcb
	(version 20260206)
	(generator "pcbnew")
	(generator_version "10.0")
	(general
		(thickness 1.6)
		(legacy_teardrops no)
	)
	(paper "A4")
	(title_block
		(title "04192023_DAF0TMB3IC0_F0TG_MB_C_brd_V02_OCP.brd")
		(comment 1 "Grand Teton / footprints 5587-5592 of 8354")
	)
	(layers
		(0 "F.Cu" signal "TOP")
		(4 "In1.Cu" signal "GND")
		(6 "In2.Cu" signal "IN1")
		(8 "In3.Cu" signal "GND1")
		(10 "In4.Cu" signal "IN2")
		(12 "In5.Cu" signal "GND2")
		(14 "In6.Cu" signal "IN3")
		(16 "In7.Cu" signal "GND3")
		(18 "In8.Cu" signal "VCC")
		(20 "In9.Cu" signal "VCC1")
		(22 "In10.Cu" signal "GND4")
		(24 "In11.Cu" signal "IN4")
		(26 "In12.Cu" signal "GND5")
		(28 "In13.Cu" signal "IN5")
		(30 "In14.Cu" signal "GND6")
		(32 "In15.Cu" signal "IN6")
		(34 "In16.Cu" signal "GND7")
		(2 "B.Cu" signal "BOTTOM")
		(9 "F.Adhes" user "F.Adhesive")
		(11 "B.Adhes" user "B.Adhesive")
		(13 "F.Paste" user "Package Geometry/Pastemask Top")
		(15 "B.Paste" user "Package Geometry/Pastemask Bottom")
		(5 "F.SilkS" user "Ref Des/Silkscreen Top")
		(7 "B.SilkS" user "Ref Des/Silkscreen Bottom")
		(1 "F.Mask" user "Board Geometry/Soldermask Top")
		(3 "B.Mask" user "Board Geometry/Soldermask Bottom")
		(17 "Dwgs.User" user "User.Drawings")
		(19 "Cmts.User" user "User.Comments")
		(21 "Eco1.User" user "User.Eco1")
		(23 "Eco2.User" user "User.Eco2")
		(25 "Edge.Cuts" user "Board Geometry/Outline")
		(27 "Margin" user)
		(31 "F.CrtYd" user "Package Geometry/Place Bound Top")
		(29 "B.CrtYd" user "Package Geometry/Place Bound Bottom")
		(35 "F.Fab" user "Ref Des/Assembly Top")
		(33 "B.Fab" user "Ref Des/Assembly Bottom")
	)
	(footprint ""
		(layer "B.Cu")
		(at 178.241452 -133.2738)
		(property "Reference" "R16"
			(at 0 0 0)
			(layer "B.SilkS")
			(hide yes)
			(effects
				(font
					(size 1.27 1.27)
				)
				(justify mirror)
			)
		)
		(property "Value" ""
			(at 0 0 0)
			(layer "B.Fab")
			(effects
				(font
					(size 1.27 1.27)
				)
				(justify mirror)
			)
		)
		(duplicate_pad_numbers_are_jumpers no)
		(fp_line
			(start -0.7874 -0.4064)
			(end -0.7874 0.4064)
			(stroke
				(width 0.1524)
				(type default)
			)
			(layer "B.SilkS")
		)
		(fp_line
			(start -0.7874 0.4064)
			(end 0.7874 0.4064)
			(stroke
				(width 0.1524)
				(type default)
			)
			(layer "B.SilkS")
		)
		(fp_line
			(start 0.7874 -0.4064)
			(end -0.7874 -0.4064)
			(stroke
				(width 0.1524)
				(type default)
			)
			(layer "B.SilkS")
		)
		(fp_line
			(start 0.7874 0.4064)
			(end 0.7874 -0.4064)
			(stroke
				(width 0.1524)
				(type default)
			)
			(layer "B.SilkS")
		)
		(fp_line
			(start -0.67945 -0.3048)
			(end -0.67945 0.3048)
			(stroke
				(width 0.1)
				(type default)
			)
			(layer "B.Fab")
		)
		(fp_line
			(start -0.67945 0.3048)
			(end -0.120396 0.3048)
			(stroke
				(width 0.1)
				(type default)
			)
			(layer "B.Fab")
		)
		(fp_line
			(start -0.12065 -0.3048)
			(end -0.67945 -0.3048)
			(stroke
				(width 0.1)
				(type default)
			)
			(layer "B.Fab")
		)
		(fp_line
			(start -0.12065 -0.2794)
			(end -0.12065 -0.3048)
			(stroke
				(width 0.1)
				(type default)
			)
			(layer "B.Fab")
		)
		(fp_line
			(start -0.120396 0.2794)
			(end 0.12065 0.2794)
			(stroke
				(width 0.1)
				(type default)
			)
			(layer "B.Fab")
		)
		(fp_line
			(start -0.120396 0.3048)
			(end -0.120396 0.2794)
			(stroke
				(width 0.1)
				(type default)
			)
			(layer "B.Fab")
		)
		(fp_line
			(start 0.12065 -0.305054)
			(end 0.12065 -0.2794)
			(stroke
				(width 0.1)
				(type default)
			)
			(layer "B.Fab")
		)
		(fp_line
			(start 0.12065 -0.2794)
			(end -0.12065 -0.2794)
			(stroke
				(width 0.1)
				(type default)
			)
			(layer "B.Fab")
		)
		(fp_line
			(start 0.12065 0.2794)
			(end 0.12065 0.3048)
			(stroke
				(width 0.1)
				(type default)
			)
			(layer "B.Fab")
		)
		(fp_line
			(start 0.12065 0.3048)
			(end 0.67945 0.3048)
			(stroke
				(width 0.1)
				(type default)
			)
			(layer "B.Fab")
		)
		(fp_line
			(start 0.67945 -0.305054)
			(end 0.12065 -0.305054)
			(stroke
				(width 0.1)
				(type default)
			)
			(layer "B.Fab")
		)
		(fp_line
			(start 0.67945 0.3048)
			(end 0.67945 -0.305054)
			(stroke
				(width 0.1)
				(type default)
			)
			(layer "B.Fab")
		)
		(pad "1" smd circle
			(at 0.40005 0 180)
			(size 0 0)
			(layers "B.Cu" "B.Mask" "B.Paste")
			(net "RST_CPU0_PERST0_N")
		)
		(pad "2" smd circle
			(at -0.40005 0 180)
			(size 0 0)
			(layers "B.Cu" "B.Mask" "B.Paste")
			(net "GND")
		)
	)
	(footprint ""
		(layer "B.Cu")
		(at 387.291326 -398.942052 90)
		(property "Reference" "C1045"
			(at 0 0 90)
			(layer "B.SilkS")
			(hide yes)
			(effects
				(font
					(size 1.27 1.27)
				)
				(justify mirror)
			)
		)
		(property "Value" ""
			(at 0 0 90)
			(layer "B.Fab")
			(effects
				(font
					(size 1.27 1.27)
				)
				(justify mirror)
			)
		)
		(duplicate_pad_numbers_are_jumpers no)
		(fp_line
			(start 0.7874 -0.4064)
			(end -0.7874 -0.4064)
			(stroke
				(width 0.1524)
				(type default)
			)
			(layer "B.SilkS")
		)
		(fp_line
			(start -0.7874 -0.4064)
			(end -0.7874 0.4064)
			(stroke
				(width 0.1524)
				(type default)
			)
			(layer "B.SilkS")
		)
		(fp_line
			(start 0.7874 0.4064)
			(end 0.7874 -0.4064)
			(stroke
				(width 0.1524)
				(type default)
			)
			(layer "B.SilkS")
		)
		(fp_line
			(start -0.7874 0.4064)
			(end 0.7874 0.4064)
			(stroke
				(width 0.1524)
				(type default)
			)
			(layer "B.SilkS")
		)
		(fp_line
			(start 0.67945 -0.305054)
			(end 0.12065 -0.305054)
			(stroke
				(width 0.1)
				(type default)
			)
			(layer "B.Fab")
		)
		(fp_line
			(start 0.12065 -0.305054)
			(end 0.12065 -0.2794)
			(stroke
				(width 0.1)
				(type default)
			)
			(layer "B.Fab")
		)
		(fp_line
			(start -0.12065 -0.3048)
			(end -0.67945 -0.3048)
			(stroke
				(width 0.1)
				(type default)
			)
			(layer "B.Fab")
		)
		(fp_line
			(start -0.67945 -0.3048)
			(end -0.67945 0.3048)
			(stroke
				(width 0.1)
				(type default)
			)
			(layer "B.Fab")
		)
		(fp_line
			(start 0.12065 -0.2794)
			(end -0.12065 -0.2794)
			(stroke
				(width 0.1)
				(type default)
			)
			(layer "B.Fab")
		)
		(fp_line
			(start -0.12065 -0.2794)
			(end -0.12065 -0.3048)
			(stroke
				(width 0.1)
				(type default)
			)
			(layer "B.Fab")
		)
		(fp_line
			(start 0.12065 0.2794)
			(end 0.12065 0.3048)
			(stroke
				(width 0.1)
				(type default)
			)
			(layer "B.Fab")
		)
		(fp_line
			(start -0.120396 0.2794)
			(end 0.12065 0.2794)
			(stroke
				(width 0.1)
				(type default)
			)
			(layer "B.Fab")
		)
		(fp_line
			(start 0.67945 0.3048)
			(end 0.67945 -0.305054)
			(stroke
				(width 0.1)
				(type default)
			)
			(layer "B.Fab")
		)
		(fp_line
			(start 0.12065 0.3048)
			(end 0.67945 0.3048)
			(stroke
				(width 0.1)
				(type default)
			)
			(layer "B.Fab")
		)
		(fp_line
			(start -0.120396 0.3048)
			(end -0.120396 0.2794)
			(stroke
				(width 0.1)
				(type default)
			)
			(layer "B.Fab")
		)
		(fp_line
			(start -0.67945 0.3048)
			(end -0.120396 0.3048)
			(stroke
				(width 0.1)
				(type default)
			)
			(layer "B.Fab")
		)
		(pad "1" smd circle
			(at 0.40005 0 270)
			(size 0 0)
			(layers "B.Cu" "B.Mask" "B.Paste")
			(net "P0V9_CPU0_RT3_2A")
		)
		(pad "2" smd circle
			(at -0.40005 0 270)
			(size 0 0)
			(layers "B.Cu" "B.Mask" "B.Paste")
			(net "GND")
		)
	)
	(footprint ""
		(layer "B.Cu")
		(at 203.045314 -78.247748 180)
		(property "Reference" "R3244"
			(at 0 0 0)
			(layer "B.SilkS")
			(hide yes)
			(effects
				(font
					(size 1.27 1.27)
				)
				(justify mirror)
			)
		)
		(property "Value" ""
			(at 0 0 0)
			(layer "B.Fab")
			(effects
				(font
					(size 1.27 1.27)
				)
				(justify mirror)
			)
		)
		(duplicate_pad_numbers_are_jumpers no)
		(fp_line
			(start 0.7874 0.4064)
			(end 0.7874 -0.4064)
			(stroke
				(width 0.1524)
				(type default)
			)
			(layer "B.SilkS")
		)
		(fp_line
			(start 0.7874 -0.4064)
			(end -0.7874 -0.4064)
			(stroke
				(width 0.1524)
				(type default)
			)
			(layer "B.SilkS")
		)
		(fp_line
			(start -0.7874 0.4064)
			(end 0.7874 0.4064)
			(stroke
				(width 0.1524)
				(type default)
			)
			(layer "B.SilkS")
		)
		(fp_line
			(start -0.7874 -0.4064)
			(end -0.7874 0.4064)
			(stroke
				(width 0.1524)
				(type default)
			)
			(layer "B.SilkS")
		)
		(fp_line
			(start 0.67945 0.3048)
			(end 0.67945 -0.305054)
			(stroke
				(width 0.1)
				(type default)
			)
			(layer "B.Fab")
		)
		(fp_line
			(start 0.67945 -0.305054)
			(end 0.12065 -0.305054)
			(stroke
				(width 0.1)
				(type default)
			)
			(layer "B.Fab")
		)
		(fp_line
			(start 0.12065 0.3048)
			(end 0.67945 0.3048)
			(stroke
				(width 0.1)
				(type default)
			)
			(layer "B.Fab")
		)
		(fp_line
			(start 0.12065 0.2794)
			(end 0.12065 0.3048)
			(stroke
				(width 0.1)
				(type default)
			)
			(layer "B.Fab")
		)
		(fp_line
			(start 0.12065 -0.2794)
			(end -0.12065 -0.2794)
			(stroke
				(width 0.1)
				(type default)
			)
			(layer "B.Fab")
		)
		(fp_line
			(start 0.12065 -0.305054)
			(end 0.12065 -0.2794)
			(stroke
				(width 0.1)
				(type default)
			)
			(layer "B.Fab")
		)
		(fp_line
			(start -0.120396 0.3048)
			(end -0.120396 0.2794)
			(stroke
				(width 0.1)
				(type default)
			)
			(layer "B.Fab")
		)
		(fp_line
			(start -0.120396 0.2794)
			(end 0.12065 0.2794)
			(stroke
				(width 0.1)
				(type default)
			)
			(layer "B.Fab")
		)
		(fp_line
			(start -0.12065 -0.2794)
			(end -0.12065 -0.3048)
			(stroke
				(width 0.1)
				(type default)
			)
			(layer "B.Fab")
		)
		(fp_line
			(start -0.12065 -0.3048)
			(end -0.67945 -0.3048)
			(stroke
				(width 0.1)
				(type default)
			)
			(layer "B.Fab")
		)
		(fp_line
			(start -0.67945 0.3048)
			(end -0.120396 0.3048)
			(stroke
				(width 0.1)
				(type default)
			)
			(layer "B.Fab")
		)
		(fp_line
			(start -0.67945 -0.3048)
			(end -0.67945 0.3048)
			(stroke
				(width 0.1)
				(type default)
			)
			(layer "B.Fab")
		)
		(pad "1" smd circle
			(at 0.40005 0)
			(size 0 0)
			(layers "B.Cu" "B.Mask" "B.Paste")
			(net "OCP_V3_2_RBT_ARB_OUT")
		)
		(pad "2" smd circle
			(at -0.40005 0)
			(size 0 0)
			(layers "B.Cu" "B.Mask" "B.Paste")
			(net "OCP_V3_2_RBT_ARB_IN_R")
		)
	)
	(footprint ""
		(layer "B.Cu")
		(at 116.702078 -26.025856 90)
		(property "Reference" "C6120"
			(at 0 0 90)
			(layer "B.SilkS")
			(hide yes)
			(effects
				(font
					(size 1.27 1.27)
				)
				(justify mirror)
			)
		)
		(property "Value" ""
			(at 0 0 90)
			(layer "B.Fab")
			(effects
				(font
					(size 1.27 1.27)
				)
				(justify mirror)
			)
		)
		(duplicate_pad_numbers_are_jumpers no)
		(fp_line
			(start 0.7874 -0.4064)
			(end -0.7874 -0.4064)
			(stroke
				(width 0.1524)
				(type default)
			)
			(layer "B.SilkS")
		)
		(fp_line
			(start -0.7874 -0.4064)
			(end -0.7874 0.4064)
			(stroke
				(width 0.1524)
				(type default)
			)
			(layer "B.SilkS")
		)
		(fp_line
			(start 0.7874 0.4064)
			(end 0.7874 -0.4064)
			(stroke
				(width 0.1524)
				(type default)
			)
			(layer "B.SilkS")
		)
		(fp_line
			(start -0.7874 0.4064)
			(end 0.7874 0.4064)
			(stroke
				(width 0.1524)
				(type default)
			)
			(layer "B.SilkS")
		)
		(fp_line
			(start 0.67945 -0.305054)
			(end 0.12065 -0.305054)
			(stroke
				(width 0.1)
				(type default)
			)
			(layer "B.Fab")
		)
		(fp_line
			(start 0.12065 -0.305054)
			(end 0.12065 -0.2794)
			(stroke
				(width 0.1)
				(type default)
			)
			(layer "B.Fab")
		)
		(fp_line
			(start -0.12065 -0.3048)
			(end -0.67945 -0.3048)
			(stroke
				(width 0.1)
				(type default)
			)
			(layer "B.Fab")
		)
		(fp_line
			(start -0.67945 -0.3048)
			(end -0.67945 0.3048)
			(stroke
				(width 0.1)
				(type default)
			)
			(layer "B.Fab")
		)
		(fp_line
			(start 0.12065 -0.2794)
			(end -0.12065 -0.2794)
			(stroke
				(width 0.1)
				(type default)
			)
			(layer "B.Fab")
		)
		(fp_line
			(start -0.12065 -0.2794)
			(end -0.12065 -0.3048)
			(stroke
				(width 0.1)
				(type default)
			)
			(layer "B.Fab")
		)
		(fp_line
			(start 0.12065 0.2794)
			(end 0.12065 0.3048)
			(stroke
				(width 0.1)
				(type default)
			)
			(layer "B.Fab")
		)
		(fp_line
			(start -0.120396 0.2794)
			(end 0.12065 0.2794)
			(stroke
				(width 0.1)
				(type default)
			)
			(layer "B.Fab")
		)
		(fp_line
			(start 0.67945 0.3048)
			(end 0.67945 -0.305054)
			(stroke
				(width 0.1)
				(type default)
			)
			(layer "B.Fab")
		)
		(fp_line
			(start 0.12065 0.3048)
			(end 0.67945 0.3048)
			(stroke
				(width 0.1)
				(type default)
			)
			(layer "B.Fab")
		)
		(fp_line
			(start -0.120396 0.3048)
			(end -0.120396 0.2794)
			(stroke
				(width 0.1)
				(type default)
			)
			(layer "B.Fab")
		)
		(fp_line
			(start -0.67945 0.3048)
			(end -0.120396 0.3048)
			(stroke
				(width 0.1)
				(type default)
			)
			(layer "B.Fab")
		)
		(pad "1" smd circle
			(at 0.40005 0 270)
			(size 0 0)
			(layers "B.Cu" "B.Mask" "B.Paste")
			(net "P1V2_CPU0_USB2_DVDD12")
		)
		(pad "2" smd circle
			(at -0.40005 0 270)
			(size 0 0)
			(layers "B.Cu" "B.Mask" "B.Paste")
			(net "GND")
		)
	)
	(footprint ""
		(layer "B.Cu")
		(at 356.406958 -249.36831 180)
		(property "Reference" "C268"
			(at 0 0 0)
			(layer "B.SilkS")
			(hide yes)
			(effects
				(font
					(size 1.27 1.27)
				)
				(justify mirror)
			)
		)
		(property "Value" ""
			(at 0 0 0)
			(layer "B.Fab")
			(effects
				(font
					(size 1.27 1.27)
				)
				(justify mirror)
			)
		)
		(duplicate_pad_numbers_are_jumpers no)
		(fp_line
			(start 0.7874 0.4064)
			(end 0.7874 -0.4064)
			(stroke
				(width 0.1524)
				(type default)
			)
			(layer "B.SilkS")
		)
		(fp_line
			(start 0.7874 -0.4064)
			(end -0.7874 -0.4064)
			(stroke
				(width 0.1524)
				(type default)
			)
			(layer "B.SilkS")
		)
		(fp_line
			(start -0.7874 0.4064)
			(end 0.7874 0.4064)
			(stroke
				(width 0.1524)
				(type default)
			)
			(layer "B.SilkS")
		)
		(fp_line
			(start -0.7874 -0.4064)
			(end -0.7874 0.4064)
			(stroke
				(width 0.1524)
				(type default)
			)
			(layer "B.SilkS")
		)
		(fp_line
			(start 0.67945 0.3048)
			(end 0.67945 -0.305054)
			(stroke
				(width 0.1)
				(type default)
			)
			(layer "B.Fab")
		)
		(fp_line
			(start 0.67945 -0.305054)
			(end 0.12065 -0.305054)
			(stroke
				(width 0.1)
				(type default)
			)
			(layer "B.Fab")
		)
		(fp_line
			(start 0.12065 0.3048)
			(end 0.67945 0.3048)
			(stroke
				(width 0.1)
				(type default)
			)
			(layer "B.Fab")
		)
		(fp_line
			(start 0.12065 0.2794)
			(end 0.12065 0.3048)
			(stroke
				(width 0.1)
				(type default)
			)
			(layer "B.Fab")
		)
		(fp_line
			(start 0.12065 -0.2794)
			(end -0.12065 -0.2794)
			(stroke
				(width 0.1)
				(type default)
			)
			(layer "B.Fab")
		)
		(fp_line
			(start 0.12065 -0.305054)
			(end 0.12065 -0.2794)
			(stroke
				(width 0.1)
				(type default)
			)
			(layer "B.Fab")
		)
		(fp_line
			(start -0.120396 0.3048)
			(end -0.120396 0.2794)
			(stroke
				(width 0.1)
				(type default)
			)
			(layer "B.Fab")
		)
		(fp_line
			(start -0.120396 0.2794)
			(end 0.12065 0.2794)
			(stroke
				(width 0.1)
				(type default)
			)
			(layer "B.Fab")
		)
		(fp_line
			(start -0.12065 -0.2794)
			(end -0.12065 -0.3048)
			(stroke
				(width 0.1)
				(type default)
			)
			(layer "B.Fab")
		)
		(fp_line
			(start -0.12065 -0.3048)
			(end -0.67945 -0.3048)
			(stroke
				(width 0.1)
				(type default)
			)
			(layer "B.Fab")
		)
		(fp_line
			(start -0.67945 0.3048)
			(end -0.120396 0.3048)
			(stroke
				(width 0.1)
				(type default)
			)
			(layer "B.Fab")
		)
		(fp_line
			(start -0.67945 -0.3048)
			(end -0.67945 0.3048)
			(stroke
				(width 0.1)
				(type default)
			)
			(layer "B.Fab")
		)
		(pad "1" smd circle
			(at 0.40005 0)
			(size 0 0)
			(layers "B.Cu" "B.Mask" "B.Paste")
			(net "PVDDCR_CPU0_P0")
		)
		(pad "2" smd circle
			(at -0.40005 0)
			(size 0 0)
			(layers "B.Cu" "B.Mask" "B.Paste")
			(net "GND")
		)
	)
	(footprint ""
		(layer "B.Cu")
		(at 370.801646 -261.935976)
		(property "Reference" "C2590"
			(at 0 0 0)
			(layer "B.SilkS")
			(hide yes)
			(effects
				(font
					(size 1.27 1.27)
				)
				(justify mirror)
			)
		)
		(property "Value" ""
			(at 0 0 0)
			(layer "B.Fab")
			(effects
				(font
					(size 1.27 1.27)
				)
				(justify mirror)
			)
		)
		(duplicate_pad_numbers_are_jumpers no)
		(fp_line
			(start -0.7874 -0.4064)
			(end -0.7874 0.4064)
			(stroke
				(width 0.1524)
				(type default)
			)
			(layer "B.SilkS")
		)
		(fp_line
			(start -0.7874 0.4064)
			(end 0.7874 0.4064)
			(stroke
				(width 0.1524)
				(type default)
			)
			(layer "B.SilkS")
		)
		(fp_line
			(start 0.7874 -0.4064)
			(end -0.7874 -0.4064)
			(stroke
				(width 0.1524)
				(type default)
			)
			(layer "B.SilkS")
		)
		(fp_line
			(start 0.7874 0.4064)
			(end 0.7874 -0.4064)
			(stroke
				(width 0.1524)
				(type default)
			)
			(layer "B.SilkS")
		)
		(fp_line
			(start -0.67945 -0.3048)
			(end -0.67945 0.3048)
			(stroke
				(width 0.1)
				(type default)
			)
			(layer "B.Fab")
		)
		(fp_line
			(start -0.67945 0.3048)
			(end -0.120396 0.3048)
			(stroke
				(width 0.1)
				(type default)
			)
			(layer "B.Fab")
		)
		(fp_line
			(start -0.12065 -0.3048)
			(end -0.67945 -0.3048)
			(stroke
				(width 0.1)
				(type default)
			)
			(layer "B.Fab")
		)
		(fp_line
			(start -0.12065 -0.2794)
			(end -0.12065 -0.3048)
			(stroke
				(width 0.1)
				(type default)
			)
			(layer "B.Fab")
		)
		(fp_line
			(start -0.120396 0.2794)
			(end 0.12065 0.2794)
			(stroke
				(width 0.1)
				(type default)
			)
			(layer "B.Fab")
		)
		(fp_line
			(start -0.120396 0.3048)
			(end -0.120396 0.2794)
			(stroke
				(width 0.1)
				(type default)
			)
			(layer "B.Fab")
		)
		(fp_line
			(start 0.12065 -0.305054)
			(end 0.12065 -0.2794)
			(stroke
				(width 0.1)
				(type default)
			)
			(layer "B.Fab")
		)
		(fp_line
			(start 0.12065 -0.2794)
			(end -0.12065 -0.2794)
			(stroke
				(width 0.1)
				(type default)
			)
			(layer "B.Fab")
		)
		(fp_line
			(start 0.12065 0.2794)
			(end 0.12065 0.3048)
			(stroke
				(width 0.1)
				(type default)
			)
			(layer "B.Fab")
		)
		(fp_line
			(start 0.12065 0.3048)
			(end 0.67945 0.3048)
			(stroke
				(width 0.1)
				(type default)
			)
			(layer "B.Fab")
		)
		(fp_line
			(start 0.67945 -0.305054)
			(end 0.12065 -0.305054)
			(stroke
				(width 0.1)
				(type default)
			)
			(layer "B.Fab")
		)
		(fp_line
			(start 0.67945 0.3048)
			(end 0.67945 -0.305054)
			(stroke
				(width 0.1)
				(type default)
			)
			(layer "B.Fab")
		)
		(pad "1" smd circle
			(at 0.40005 0 180)
			(size 0 0)
			(layers "B.Cu" "B.Mask" "B.Paste")
			(net "PVDDCR_SOC_P0")
		)
		(pad "2" smd circle
			(at -0.40005 0 180)
			(size 0 0)
			(layers "B.Cu" "B.Mask" "B.Paste")
			(net "GND")
		)
	)
)
